(kicad_pcb
	(version 20260206)
	(generator "pcbnew")
	(generator_version "10.0")
	(general
		(thickness 1.6)
		(legacy_teardrops no)
	)
	(paper "A4")
	(title_block
		(title "Wiwynn_Tioga_Pass_MB.brd")
		(comment 1 "Tioga Pass / footprints 585-586 of 4770")
	)
	(layers
		(0 "F.Cu" signal "TOP")
		(4 "In1.Cu" signal "L2GND")
		(6 "In2.Cu" signal "L3")
		(8 "In3.Cu" signal "L4GND")
		(10 "In4.Cu" signal "L5")
		(12 "In5.Cu" signal "L6GND")
		(14 "In6.Cu" signal "L7VCC")
		(16 "In7.Cu" signal "L8VCC")
		(18 "In8.Cu" signal "L9GND")
		(20 "In9.Cu" signal "L10")
		(22 "In10.Cu" signal "L11GND")
		(24 "In11.Cu" signal "L12")
		(26 "In12.Cu" signal "L13GND")
		(2 "B.Cu" signal "BOTTOM")
		(9 "F.Adhes" user "F.Adhesive")
		(11 "B.Adhes" user "B.Adhesive")
		(13 "F.Paste" user "Package Geometry/Pastemask Top")
		(15 "B.Paste" user "Package Geometry/Pastemask Bottom")
		(5 "F.SilkS" user "Ref Des/Silkscreen Top")
		(7 "B.SilkS" user "Ref Des/Silkscreen Bottom")
		(1 "F.Mask" user "Board Geometry/Soldermask Top")
		(3 "B.Mask" user "Board Geometry/Soldermask Bottom")
		(17 "Dwgs.User" user "User.Drawings")
		(19 "Cmts.User" user "User.Comments")
		(21 "Eco1.User" user "User.Eco1")
		(23 "Eco2.User" user "User.Eco2")
		(25 "Edge.Cuts" user "Board Geometry/Outline")
		(27 "Margin" user)
		(31 "F.CrtYd" user "Package Geometry/Place Bound Top")
		(29 "B.CrtYd" user "Package Geometry/Place Bound Bottom")
		(35 "F.Fab" user "Ref Des/Assembly Top")
		(33 "B.Fab" user "Ref Des/Assembly Bottom")
	)
	(footprint ""
		(layer "F.Cu")
		(at 166.116 -86.868 180)
		(property "Reference" "R4D2"
			(at 0 0 180)
			(layer "F.SilkS")
			(hide yes)
			(effects
				(font
					(size 1.27 1.27)
				)
			)
		)
		(property "Value" ""
			(at 0 0 180)
			(layer "F.Fab")
			(effects
				(font
					(size 1.27 1.27)
				)
			)
		)
		(duplicate_pad_numbers_are_jumpers no)
		(fp_poly
			(pts
				(xy -0.2794 -0.1016) (xy 0.2794 -0.1016) (xy 0.2794 0.9906) (xy -0.2794 0.9906)
			)
			(stroke
				(width 0)
				(type default)
			)
			(fill no)
			(layer "F.CrtYd")
		)
		(fp_line
			(start 0.2794 0.9906)
			(end 0.2794 -0.1016)
			(stroke
				(width 0.1)
				(type default)
			)
			(layer "F.Fab")
		)
		(fp_line
			(start 0.2794 -0.1016)
			(end -0.2794 -0.1016)
			(stroke
				(width 0.1)
				(type default)
			)
			(layer "F.Fab")
		)
		(fp_line
			(start -0.2794 0.9906)
			(end 0.2794 0.9906)
			(stroke
				(width 0.1)
				(type default)
			)
			(layer "F.Fab")
		)
		(fp_line
			(start -0.2794 -0.1016)
			(end -0.2794 0.9906)
			(stroke
				(width 0.1)
				(type default)
			)
			(layer "F.Fab")
		)
		(pad "1" smd rect
			(at 0 0 180)
			(size 0.508 0.508)
			(layers "F.Cu" "F.Mask" "F.Paste")
			(net "CLK_100M_CPU1_BCLK1_R_DP")
		)
		(pad "2" smd rect
			(at 0 0.889 180)
			(size 0.508 0.508)
			(layers "F.Cu" "F.Mask" "F.Paste")
			(net "CLK_100M_CPU1_BCLK1_DP")
		)
		(zone
			(layer "F.Cu")
			(hatch none 0.5)
			(connect_pads
				(clearance 0)
			)
			(min_thickness 0.25)
			(keepout
				(tracks not_allowed)
				(vias allowed)
				(pads allowed)
				(copperpour not_allowed)
				(footprints allowed)
			)
			(placement
				(enabled no)
				(sheetname "")
			)
			(fill
				(thermal_gap 0.5)
				(thermal_bridge_width 0.5)
				(island_removal_mode 0)
			)
			(polygon
				(pts
					(xy 166.37 -87.503) (xy 165.862 -87.503) (xy 165.862 -87.122) (xy 166.37 -87.122)
				)
			)
		)
		(zone
			(layer "F.Cu")
			(hatch none 0.5)
			(connect_pads
				(clearance 0)
			)
			(min_thickness 0.25)
			(keepout
				(tracks allowed)
				(vias not_allowed)
				(pads allowed)
				(copperpour not_allowed)
				(footprints allowed)
			)
			(placement
				(enabled no)
				(sheetname "")
			)
			(fill
				(thermal_gap 0.5)
				(thermal_bridge_width 0.5)
				(island_removal_mode 0)
			)
			(polygon
				(pts
					(xy 166.37 -87.122) (xy 165.862 -87.122) (xy 165.862 -87.503) (xy 166.37 -87.503)
				)
			)
		)
	)
	(footprint ""
		(layer "F.Cu")
		(at 80.757268 -149.8092 -90)
		(property "Reference" "C2A1"
			(at 1.848866 0.752348 270)
			(unlocked yes)
			(layer "F.SilkS")
			(effects
				(font
					(size 1.27 0.9652)
					(thickness 0.1524)
				)
			)
		)
		(property "Value" ""
			(at 0 0 270)
			(layer "F.Fab")
			(effects
				(font
					(size 1.27 1.27)
				)
			)
		)
		(duplicate_pad_numbers_are_jumpers no)
		(fp_rect
			(start -0.500126 1.598422)
			(end 0.500126 -0.201422)
			(stroke
				(width 0)
				(type default)
			)
			(fill no)
			(layer "F.CrtYd")
		)
		(fp_line
			(start -0.500126 1.598422)
			(end -0.500126 -0.201422)
			(stroke
				(width 0.1)
				(type default)
			)
			(layer "F.Fab")
		)
		(fp_line
			(start 0.500126 1.598422)
			(end -0.500126 1.598422)
			(stroke
				(width 0.1)
				(type default)
			)
			(layer "F.Fab")
		)
		(fp_line
			(start -0.500126 -0.201422)
			(end 0.500126 -0.201422)
			(stroke
				(width 0.1)
				(type default)
			)
			(layer "F.Fab")
		)
		(fp_line
			(start 0.500126 -0.201422)
			(end 0.500126 1.598422)
			(stroke
				(width 0.1)
				(type default)
			)
			(layer "F.Fab")
		)
		(pad "1" smd rect
			(at 0 0 180)
			(size 0.889 0.9906)
			(layers "F.Cu" "F.Mask" "F.Paste")
			(net "PVDDQ_KLM")
		)
		(pad "2" smd rect
			(at 0 1.397 180)
			(size 0.889 0.9906)
			(layers "F.Cu" "F.Mask" "F.Paste")
			(net "GND")
		)
		(zone
			(layer "F.Cu")
			(hatch none 0.5)
			(connect_pads
				(clearance 0)
			)
			(min_thickness 0.25)
			(keepout
				(tracks not_allowed)
				(vias allowed)
				(pads allowed)
				(copperpour not_allowed)
				(footprints allowed)
			)
			(placement
				(enabled no)
				(sheetname "")
			)
			(fill
				(thermal_gap 0.5)
				(thermal_bridge_width 0.5)
				(island_removal_mode 0)
			)
			(polygon
				(pts
					(xy 79.804768 -150.3045) (xy 79.804768 -149.3139) (xy 80.312768 -149.3139) (xy 80.312768 -150.3045)
				)
			)
		)
		(zone
			(layer "F.Cu")
			(hatch none 0.5)
			(connect_pads
				(clearance 0)
			)
			(min_thickness 0.25)
			(keepout
				(tracks allowed)
				(vias not_allowed)
				(pads allowed)
				(copperpour not_allowed)
				(footprints allowed)
			)
			(placement
				(enabled no)
				(sheetname "")
			)
			(fill
				(thermal_gap 0.5)
				(thermal_bridge_width 0.5)
				(island_removal_mode 0)
			)
			(polygon
				(pts
					(xy 79.804768 -150.3045) (xy 79.804768 -149.3139) (xy 80.312768 -149.3139) (xy 80.312768 -150.3045)
				)
			)
		)
	)
)
